(kicad_pcb
	(version 20260206)
	(generator "pcbnew")
	(generator_version "10.0")
	(general
		(thickness 1.6)
		(legacy_teardrops no)
	)
	(paper "A4")
	(title_block
		(title "Bryce Canyon_SCC_16316-1_OCP.brd")
		(comment 1 "Bryce Canyon / footprints 1128-1135 of 1561")
	)
	(layers
		(0 "F.Cu" signal "TOP")
		(4 "In1.Cu" signal "L2GND")
		(6 "In2.Cu" signal "L3")
		(8 "In3.Cu" signal "L4VCC")
		(10 "In4.Cu" signal "L5VCC")
		(12 "In5.Cu" signal "L6")
		(14 "In6.Cu" signal "L7GND")
		(2 "B.Cu" signal "BOTTOM")
		(9 "F.Adhes" user "F.Adhesive")
		(11 "B.Adhes" user "B.Adhesive")
		(13 "F.Paste" user "Package Geometry/Pastemask Top")
		(15 "B.Paste" user "Package Geometry/Pastemask Bottom")
		(5 "F.SilkS" user "Ref Des/Silkscreen Top")
		(7 "B.SilkS" user "Ref Des/Silkscreen Bottom")
		(1 "F.Mask" user "Board Geometry/Soldermask Top")
		(3 "B.Mask" user "Board Geometry/Soldermask Bottom")
		(17 "Dwgs.User" user "User.Drawings")
		(19 "Cmts.User" user "User.Comments")
		(21 "Eco1.User" user "User.Eco1")
		(23 "Eco2.User" user "User.Eco2")
		(25 "Edge.Cuts" user "Board Geometry/Outline")
		(27 "Margin" user)
		(31 "F.CrtYd" user "Package Geometry/Place Bound Top")
		(29 "B.CrtYd" user "Package Geometry/Place Bound Bottom")
		(35 "F.Fab" user "Ref Des/Assembly Top")
		(33 "B.Fab" user "Ref Des/Assembly Bottom")
	)
	(footprint ""
		(layer "B.Cu")
		(at 187.9346 -28.575 90)
		(property "Reference" "TP63"
			(at 0 0 90)
			(layer "B.SilkS")
			(hide yes)
			(effects
				(font
					(size 1.27 1.27)
				)
				(justify mirror)
			)
		)
		(property "Value" "TPAD28-2-GP"
			(at 0.0127 -1.6637 90)
			(unlocked yes)
			(layer "B.Fab")
			(hide yes)
			(effects
				(font
					(size 1.016 1.016)
					(thickness 0.1524)
				)
				(justify mirror)
			)
		)
		(property "Device Type" "TPAD28"
			(at 0.0127 -3.1877 90)
			(unlocked yes)
			(layer "B.Fab")
			(hide yes)
			(effects
				(font
					(size 1.016 1.016)
					(thickness 0.1524)
				)
				(justify mirror)
			)
		)
		(duplicate_pad_numbers_are_jumpers no)
		(fp_poly
			(pts
				(arc
					(start 0 0.3556)
					(mid 0 -0.3556)
					(end 0 0.3556)
				)
			)
			(stroke
				(width 0)
				(type default)
			)
			(fill no)
			(layer "B.CrtYd")
		)
		(fp_poly
			(pts
				(arc
					(start 0 0.6096)
					(mid 0 -0.6096)
					(end 0 0.6096)
				)
			)
			(stroke
				(width 0)
				(type default)
			)
			(fill no)
			(layer "B.Fab")
		)
		(pad "1" smd circle
			(at 0 0 270)
			(size 0.7112 0.7112)
			(layers "B.Cu" "B.Mask" "B.Paste")
			(net "IOC_GPIO_10")
		)
	)
	(footprint ""
		(layer "B.Cu")
		(at 198.755 -35.3314)
		(property "Reference" "R199"
			(at 0 0 0)
			(layer "B.SilkS")
			(hide yes)
			(effects
				(font
					(size 1.27 1.27)
				)
				(justify mirror)
			)
		)
		(property "Value" "4K7R2F-GP"
			(at -0.064008 -3.993896 0)
			(unlocked yes)
			(layer "B.Fab")
			(hide yes)
			(effects
				(font
					(size 1.016 1.016)
					(thickness 0.1524)
				)
				(justify mirror)
			)
		)
		(property "Device Type" "R402H16"
			(at -0.064008 -5.517896 0)
			(unlocked yes)
			(layer "B.Fab")
			(hide yes)
			(effects
				(font
					(size 1.016 1.016)
					(thickness 0.1524)
				)
				(justify mirror)
			)
		)
		(duplicate_pad_numbers_are_jumpers no)
		(fp_line
			(start -0.508 -0.9398)
			(end 0.508 -0.9398)
			(stroke
				(width 0.1524)
				(type default)
			)
			(layer "B.SilkS")
		)
		(fp_line
			(start 0.508 -0.9398)
			(end 0.508 0.9398)
			(stroke
				(width 0.1524)
				(type default)
			)
			(layer "B.SilkS")
		)
		(fp_rect
			(start 0.508 0.9398)
			(end -0.508 -0.9398)
			(stroke
				(width 0)
				(type default)
			)
			(fill no)
			(layer "B.CrtYd")
		)
		(fp_rect
			(start 0.508 0.9398)
			(end -0.508 -0.9398)
			(stroke
				(width 0)
				(type default)
			)
			(fill no)
			(layer "B.Fab")
		)
		(pad "1" smd custom
			(at 0 -0.4445 180)
			(size 0.1397 0.1397)
			(layers "B.Cu" "B.Mask" "B.Paste")
			(net "IOC_EEPROM_A2")
			(options
				(clearance outline)
				(anchor circle)
			)
			(primitives
				(gr_poly
					(pts
						(arc
							(start -0.1778 0.2794)
							(mid -0.249642 0.249642)
							(end -0.2794 0.1778)
						)
						(arc
							(start -0.2794 -0.1778)
							(mid -0.249642 -0.249642)
							(end -0.1778 -0.2794)
						)
						(arc
							(start 0.1778 -0.2794)
							(mid 0.249642 -0.249642)
							(end 0.2794 -0.1778)
						)
						(arc
							(start 0.2794 0.1778)
							(mid 0.249642 0.249642)
							(end 0.1778 0.2794)
						)
					)
					(width 0)
					(fill yes)
				)
			)
		)
		(pad "2" smd custom
			(at 0 0.4445 180)
			(size 0.1397 0.1397)
			(layers "B.Cu" "B.Mask" "B.Paste")
			(net "GND")
			(options
				(clearance outline)
				(anchor circle)
			)
			(primitives
				(gr_poly
					(pts
						(arc
							(start -0.1778 0.2794)
							(mid -0.249642 0.249642)
							(end -0.2794 0.1778)
						)
						(arc
							(start -0.2794 -0.1778)
							(mid -0.249642 -0.249642)
							(end -0.1778 -0.2794)
						)
						(arc
							(start 0.1778 -0.2794)
							(mid 0.249642 -0.249642)
							(end 0.2794 -0.1778)
						)
						(arc
							(start 0.2794 0.1778)
							(mid 0.249642 0.249642)
							(end 0.1778 0.2794)
						)
					)
					(width 0)
					(fill yes)
				)
			)
		)
	)
	(footprint ""
		(layer "B.Cu")
		(at 127.4572 -39.4716 180)
		(property "Reference" "C49"
			(at 0 0 0)
			(layer "B.SilkS")
			(hide yes)
			(effects
				(font
					(size 1.27 1.27)
				)
				(justify mirror)
			)
		)
		(property "Value" "SCD01U16V1KX-GP"
			(at 2.8321 -1.7399 180)
			(unlocked yes)
			(layer "B.Fab")
			(hide yes)
			(effects
				(font
					(size 1.016 1.016)
					(thickness 0.1524)
				)
				(justify mirror)
			)
		)
		(property "Device Type" "C0201H13"
			(at 2.8321 -3.2639 180)
			(unlocked yes)
			(layer "B.Fab")
			(hide yes)
			(effects
				(font
					(size 1.016 1.016)
					(thickness 0.1524)
				)
				(justify mirror)
			)
		)
		(duplicate_pad_numbers_are_jumpers no)
		(fp_rect
			(start 0.2794 0.6477)
			(end -0.2794 -0.6477)
			(stroke
				(width 0)
				(type default)
			)
			(fill no)
			(layer "B.CrtYd")
		)
		(fp_rect
			(start 0.2794 0.6477)
			(end -0.2794 -0.6477)
			(stroke
				(width 0)
				(type default)
			)
			(fill no)
			(layer "B.Fab")
		)
		(pad "1" smd custom
			(at 0 -0.2794)
			(size 0.0762 0.0762)
			(layers "B.Cu" "B.Mask" "B.Paste")
			(net "PHY_DPB_TO_SCC_39_DP")
			(options
				(clearance outline)
				(anchor circle)
			)
			(primitives
				(gr_poly
					(pts
						(arc
							(start 0.1524 0.127)
							(mid 0.137521 0.162921)
							(end 0.1016 0.1778)
						)
						(arc
							(start -0.1016 0.1778)
							(mid -0.137521 0.162921)
							(end -0.1524 0.127)
						)
						(arc
							(start -0.1524 -0.127)
							(mid -0.137521 -0.162921)
							(end -0.1016 -0.1778)
						)
						(arc
							(start 0.1016 -0.1778)
							(mid 0.137521 -0.162921)
							(end 0.1524 -0.127)
						)
					)
					(width 0)
					(fill yes)
				)
			)
		)
		(pad "2" smd custom
			(at 0 0.2794)
			(size 0.0762 0.0762)
			(layers "B.Cu" "B.Mask" "B.Paste")
			(net "PHY_DPB_TO_SCC_C_39_DP")
			(options
				(clearance outline)
				(anchor circle)
			)
			(primitives
				(gr_poly
					(pts
						(arc
							(start 0.1524 0.127)
							(mid 0.137521 0.162921)
							(end 0.1016 0.1778)
						)
						(arc
							(start -0.1016 0.1778)
							(mid -0.137521 0.162921)
							(end -0.1524 0.127)
						)
						(arc
							(start -0.1524 -0.127)
							(mid -0.137521 -0.162921)
							(end -0.1016 -0.1778)
						)
						(arc
							(start 0.1016 -0.1778)
							(mid 0.137521 -0.162921)
							(end 0.1524 -0.127)
						)
					)
					(width 0)
					(fill yes)
				)
			)
		)
	)
	(footprint ""
		(layer "B.Cu")
		(at 154.133804 -60.617608 -90)
		(property "Reference" "C357"
			(at 0 0 90)
			(layer "B.SilkS")
			(hide yes)
			(effects
				(font
					(size 1.27 1.27)
				)
				(justify mirror)
			)
		)
		(property "Value" "SC1U16V2KX-7-GP"
			(at -1.7526 -1.6002 270)
			(unlocked yes)
			(layer "B.Fab")
			(hide yes)
			(effects
				(font
					(size 1.016 1.016)
					(thickness 0.1524)
				)
				(justify mirror)
			)
		)
		(property "Device Type" "C402-TO0D2H24"
			(at -1.7526 -3.1242 270)
			(unlocked yes)
			(layer "B.Fab")
			(hide yes)
			(effects
				(font
					(size 1.016 1.016)
					(thickness 0.1524)
				)
				(justify mirror)
			)
		)
		(duplicate_pad_numbers_are_jumpers no)
		(fp_rect
			(start 0.4826 0.889)
			(end -0.4826 -0.889)
			(stroke
				(width 0)
				(type default)
			)
			(fill no)
			(layer "B.CrtYd")
		)
		(fp_rect
			(start 0.4826 0.889)
			(end -0.4826 -0.889)
			(stroke
				(width 0)
				(type default)
			)
			(fill no)
			(layer "B.Fab")
		)
		(pad "1" smd custom
			(at 0 -0.4572 90)
			(size 0.1524 0.1524)
			(layers "B.Cu" "B.Mask" "B.Paste")
			(net "SYS_PLL_VDD")
			(options
				(clearance outline)
				(anchor circle)
			)
			(primitives
				(gr_poly
					(pts
						(arc
							(start -0.254 -0.3048)
							(mid -0.325842 -0.275042)
							(end -0.3556 -0.2032)
						)
						(arc
							(start -0.3556 0.2032)
							(mid -0.325842 0.275042)
							(end -0.254 0.3048)
						)
						(arc
							(start 0.254 0.3048)
							(mid 0.325842 0.275042)
							(end 0.3556 0.2032)
						)
						(arc
							(start 0.3556 -0.2032)
							(mid 0.325842 -0.275042)
							(end 0.254 -0.3048)
						)
					)
					(width 0)
					(fill yes)
				)
			)
		)
		(pad "2" smd custom
			(at 0 0.4572 90)
			(size 0.1524 0.1524)
			(layers "B.Cu" "B.Mask" "B.Paste")
			(net "GND")
			(options
				(clearance outline)
				(anchor circle)
			)
			(primitives
				(gr_poly
					(pts
						(arc
							(start -0.254 -0.3048)
							(mid -0.325842 -0.275042)
							(end -0.3556 -0.2032)
						)
						(arc
							(start -0.3556 0.2032)
							(mid -0.325842 0.275042)
							(end -0.254 0.3048)
						)
						(arc
							(start 0.254 0.3048)
							(mid 0.325842 0.275042)
							(end 0.3556 0.2032)
						)
						(arc
							(start 0.3556 -0.2032)
							(mid 0.325842 -0.275042)
							(end 0.254 -0.3048)
						)
					)
					(width 0)
					(fill yes)
				)
			)
		)
	)
	(footprint ""
		(layer "B.Cu")
		(at 202.819 -35.3314)
		(property "Reference" "R198"
			(at 0 0 0)
			(layer "B.SilkS")
			(hide yes)
			(effects
				(font
					(size 1.27 1.27)
				)
				(justify mirror)
			)
		)
		(property "Value" "4K7R2F-GP"
			(at -0.064008 -3.993896 0)
			(unlocked yes)
			(layer "B.Fab")
			(hide yes)
			(effects
				(font
					(size 1.016 1.016)
					(thickness 0.1524)
				)
				(justify mirror)
			)
		)
		(property "Device Type" "R402H16"
			(at -0.064008 -5.517896 0)
			(unlocked yes)
			(layer "B.Fab")
			(hide yes)
			(effects
				(font
					(size 1.016 1.016)
					(thickness 0.1524)
				)
				(justify mirror)
			)
		)
		(duplicate_pad_numbers_are_jumpers no)
		(fp_line
			(start -0.508 -0.9398)
			(end 0.508 -0.9398)
			(stroke
				(width 0.1524)
				(type default)
			)
			(layer "B.SilkS")
		)
		(fp_line
			(start 0.508 -0.9398)
			(end 0.508 0.9398)
			(stroke
				(width 0.1524)
				(type default)
			)
			(layer "B.SilkS")
		)
		(fp_rect
			(start 0.508 0.9398)
			(end -0.508 -0.9398)
			(stroke
				(width 0)
				(type default)
			)
			(fill no)
			(layer "B.CrtYd")
		)
		(fp_rect
			(start 0.508 0.9398)
			(end -0.508 -0.9398)
			(stroke
				(width 0)
				(type default)
			)
			(fill no)
			(layer "B.Fab")
		)
		(pad "1" smd custom
			(at 0 -0.4445 180)
			(size 0.1397 0.1397)
			(layers "B.Cu" "B.Mask" "B.Paste")
			(net "IOC_EEPROM_A0")
			(options
				(clearance outline)
				(anchor circle)
			)
			(primitives
				(gr_poly
					(pts
						(arc
							(start -0.1778 0.2794)
							(mid -0.249642 0.249642)
							(end -0.2794 0.1778)
						)
						(arc
							(start -0.2794 -0.1778)
							(mid -0.249642 -0.249642)
							(end -0.1778 -0.2794)
						)
						(arc
							(start 0.1778 -0.2794)
							(mid 0.249642 -0.249642)
							(end 0.2794 -0.1778)
						)
						(arc
							(start 0.2794 0.1778)
							(mid 0.249642 0.249642)
							(end 0.1778 0.2794)
						)
					)
					(width 0)
					(fill yes)
				)
			)
		)
		(pad "2" smd custom
			(at 0 0.4445 180)
			(size 0.1397 0.1397)
			(layers "B.Cu" "B.Mask" "B.Paste")
			(net "GND")
			(options
				(clearance outline)
				(anchor circle)
			)
			(primitives
				(gr_poly
					(pts
						(arc
							(start -0.1778 0.2794)
							(mid -0.249642 0.249642)
							(end -0.2794 0.1778)
						)
						(arc
							(start -0.2794 -0.1778)
							(mid -0.249642 -0.249642)
							(end -0.1778 -0.2794)
						)
						(arc
							(start 0.1778 -0.2794)
							(mid 0.249642 -0.249642)
							(end 0.2794 -0.1778)
						)
						(arc
							(start 0.2794 0.1778)
							(mid 0.249642 0.249642)
							(end 0.1778 0.2794)
						)
					)
					(width 0)
					(fill yes)
				)
			)
		)
	)
	(footprint ""
		(layer "B.Cu")
		(at 104.06888 -85.25002 90)
		(property "Reference" "R569"
			(at 0 0 90)
			(layer "B.SilkS")
			(hide yes)
			(effects
				(font
					(size 1.27 1.27)
				)
				(justify mirror)
			)
		)
		(property "Value" "10KR2F-2-GP"
			(at -0.064008 -3.993896 90)
			(unlocked yes)
			(layer "B.Fab")
			(hide yes)
			(effects
				(font
					(size 1.016 1.016)
					(thickness 0.1524)
				)
				(justify mirror)
			)
		)
		(property "Device Type" "R402H16"
			(at -0.064008 -5.517896 90)
			(unlocked yes)
			(layer "B.Fab")
			(hide yes)
			(effects
				(font
					(size 1.016 1.016)
					(thickness 0.1524)
				)
				(justify mirror)
			)
		)
		(duplicate_pad_numbers_are_jumpers no)
		(fp_line
			(start 0.508 -0.9398)
			(end 0.508 0.9398)
			(stroke
				(width 0.1524)
				(type default)
			)
			(layer "B.SilkS")
		)
		(fp_line
			(start -0.508 -0.9398)
			(end 0.508 -0.9398)
			(stroke
				(width 0.1524)
				(type default)
			)
			(layer "B.SilkS")
		)
		(fp_rect
			(start 0.508 0.9398)
			(end -0.508 -0.9398)
			(stroke
				(width 0)
				(type default)
			)
			(fill no)
			(layer "B.CrtYd")
		)
		(fp_rect
			(start 0.508 0.9398)
			(end -0.508 -0.9398)
			(stroke
				(width 0)
				(type default)
			)
			(fill no)
			(layer "B.Fab")
		)
		(pad "1" smd custom
			(at 0 -0.4445 270)
			(size 0.1397 0.1397)
			(layers "B.Cu" "B.Mask" "B.Paste")
			(net "SYS_PWR_LED_LS_N")
			(options
				(clearance outline)
				(anchor circle)
			)
			(primitives
				(gr_poly
					(pts
						(arc
							(start -0.1778 0.2794)
							(mid -0.249642 0.249642)
							(end -0.2794 0.1778)
						)
						(arc
							(start -0.2794 -0.1778)
							(mid -0.249642 -0.249642)
							(end -0.1778 -0.2794)
						)
						(arc
							(start 0.1778 -0.2794)
							(mid 0.249642 -0.249642)
							(end 0.2794 -0.1778)
						)
						(arc
							(start 0.2794 0.1778)
							(mid 0.249642 0.249642)
							(end 0.1778 0.2794)
						)
					)
					(width 0)
					(fill yes)
				)
			)
		)
		(pad "2" smd custom
			(at 0 0.4445 270)
			(size 0.1397 0.1397)
			(layers "B.Cu" "B.Mask" "B.Paste")
			(net "GND")
			(options
				(clearance outline)
				(anchor circle)
			)
			(primitives
				(gr_poly
					(pts
						(arc
							(start -0.1778 0.2794)
							(mid -0.249642 0.249642)
							(end -0.2794 0.1778)
						)
						(arc
							(start -0.2794 -0.1778)
							(mid -0.249642 -0.249642)
							(end -0.1778 -0.2794)
						)
						(arc
							(start 0.1778 -0.2794)
							(mid 0.249642 -0.249642)
							(end 0.2794 -0.1778)
						)
						(arc
							(start 0.2794 0.1778)
							(mid 0.249642 0.249642)
							(end 0.1778 0.2794)
						)
					)
					(width 0)
					(fill yes)
				)
			)
		)
	)
	(footprint ""
		(layer "B.Cu")
		(at 179.441348 -41.329102 90)
		(property "Reference" "C441"
			(at 0 0 90)
			(layer "B.SilkS")
			(hide yes)
			(effects
				(font
					(size 1.27 1.27)
				)
				(justify mirror)
			)
		)
		(property "Value" "SCD1U6D3V1KX-GP"
			(at 2.8321 -1.7399 90)
			(unlocked yes)
			(layer "B.Fab")
			(hide yes)
			(effects
				(font
					(size 1.016 1.016)
					(thickness 0.1524)
				)
				(justify mirror)
			)
		)
		(property "Device Type" "C0201H13"
			(at 2.8321 -3.2639 90)
			(unlocked yes)
			(layer "B.Fab")
			(hide yes)
			(effects
				(font
					(size 1.016 1.016)
					(thickness 0.1524)
				)
				(justify mirror)
			)
		)
		(duplicate_pad_numbers_are_jumpers no)
		(fp_rect
			(start 0.2794 0.6477)
			(end -0.2794 -0.6477)
			(stroke
				(width 0)
				(type default)
			)
			(fill no)
			(layer "B.CrtYd")
		)
		(fp_rect
			(start 0.2794 0.6477)
			(end -0.2794 -0.6477)
			(stroke
				(width 0)
				(type default)
			)
			(fill no)
			(layer "B.Fab")
		)
		(pad "1" smd custom
			(at 0 -0.2794 270)
			(size 0.0762 0.0762)
			(layers "B.Cu" "B.Mask" "B.Paste")
			(net "P0V975")
			(options
				(clearance outline)
				(anchor circle)
			)
			(primitives
				(gr_poly
					(pts
						(arc
							(start 0.1524 0.127)
							(mid 0.137521 0.162921)
							(end 0.1016 0.1778)
						)
						(arc
							(start -0.1016 0.1778)
							(mid -0.137521 0.162921)
							(end -0.1524 0.127)
						)
						(arc
							(start -0.1524 -0.127)
							(mid -0.137521 -0.162921)
							(end -0.1016 -0.1778)
						)
						(arc
							(start 0.1016 -0.1778)
							(mid 0.137521 -0.162921)
							(end 0.1524 -0.127)
						)
					)
					(width 0)
					(fill yes)
				)
			)
		)
		(pad "2" smd custom
			(at 0 0.2794 270)
			(size 0.0762 0.0762)
			(layers "B.Cu" "B.Mask" "B.Paste")
			(net "GND")
			(options
				(clearance outline)
				(anchor circle)
			)
			(primitives
				(gr_poly
					(pts
						(arc
							(start 0.1524 0.127)
							(mid 0.137521 0.162921)
							(end 0.1016 0.1778)
						)
						(arc
							(start -0.1016 0.1778)
							(mid -0.137521 0.162921)
							(end -0.1524 0.127)
						)
						(arc
							(start -0.1524 -0.127)
							(mid -0.137521 -0.162921)
							(end -0.1016 -0.1778)
						)
						(arc
							(start 0.1016 -0.1778)
							(mid 0.137521 -0.162921)
							(end 0.1524 -0.127)
						)
					)
					(width 0)
					(fill yes)
				)
			)
		)
	)
	(footprint ""
		(layer "B.Cu")
		(at 176.1617 -43.4721 90)
		(property "Reference" "C422"
			(at 0 0 90)
			(layer "B.SilkS")
			(hide yes)
			(effects
				(font
					(size 1.27 1.27)
				)
				(justify mirror)
			)
		)
		(property "Value" "SCD1U6D3V1KX-GP"
			(at 2.8321 -1.7399 90)
			(unlocked yes)
			(layer "B.Fab")
			(hide yes)
			(effects
				(font
					(size 1.016 1.016)
					(thickness 0.1524)
				)
				(justify mirror)
			)
		)
		(property "Device Type" "C0201H13"
			(at 2.8321 -3.2639 90)
			(unlocked yes)
			(layer "B.Fab")
			(hide yes)
			(effects
				(font
					(size 1.016 1.016)
					(thickness 0.1524)
				)
				(justify mirror)
			)
		)
		(duplicate_pad_numbers_are_jumpers no)
		(fp_rect
			(start 0.2794 0.6477)
			(end -0.2794 -0.6477)
			(stroke
				(width 0)
				(type default)
			)
			(fill no)
			(layer "B.CrtYd")
		)
		(fp_rect
			(start 0.2794 0.6477)
			(end -0.2794 -0.6477)
			(stroke
				(width 0)
				(type default)
			)
			(fill no)
			(layer "B.Fab")
		)
		(pad "1" smd custom
			(at 0 -0.2794 270)
			(size 0.0762 0.0762)
			(layers "B.Cu" "B.Mask" "B.Paste")
			(net "P0V975")
			(options
				(clearance outline)
				(anchor circle)
			)
			(primitives
				(gr_poly
					(pts
						(arc
							(start 0.1524 0.127)
							(mid 0.137521 0.162921)
							(end 0.1016 0.1778)
						)
						(arc
							(start -0.1016 0.1778)
							(mid -0.137521 0.162921)
							(end -0.1524 0.127)
						)
						(arc
							(start -0.1524 -0.127)
							(mid -0.137521 -0.162921)
							(end -0.1016 -0.1778)
						)
						(arc
							(start 0.1016 -0.1778)
							(mid 0.137521 -0.162921)
							(end 0.1524 -0.127)
						)
					)
					(width 0)
					(fill yes)
				)
			)
		)
		(pad "2" smd custom
			(at 0 0.2794 270)
			(size 0.0762 0.0762)
			(layers "B.Cu" "B.Mask" "B.Paste")
			(net "GND")
			(options
				(clearance outline)
				(anchor circle)
			)
			(primitives
				(gr_poly
					(pts
						(arc
							(start 0.1524 0.127)
							(mid 0.137521 0.162921)
							(end 0.1016 0.1778)
						)
						(arc
							(start -0.1016 0.1778)
							(mid -0.137521 0.162921)
							(end -0.1524 0.127)
						)
						(arc
							(start -0.1524 -0.127)
							(mid -0.137521 -0.162921)
							(end -0.1016 -0.1778)
						)
						(arc
							(start 0.1016 -0.1778)
							(mid 0.137521 -0.162921)
							(end 0.1524 -0.127)
						)
					)
					(width 0)
					(fill yes)
				)
			)
		)
	)
)
